(kicad_pcb
	(version 20260206)
	(generator "pcbnew")
	(generator_version "10.0")
	(general
		(thickness 1.6)
		(legacy_teardrops no)
	)
	(paper "A4")
	(title_block
		(title "03242023_DA0F0TMBIJ0_F0T_Motherboard_J_brd_V01_OCP.brd")
		(comment 1 "Grand Teton / footprint 3039 of 6105 (U2), pads 3901-4000 of 4677")
	)
	(layers
		(0 "F.Cu" signal "TOP")
		(4 "In1.Cu" signal "GND")
		(6 "In2.Cu" signal "IN1")
		(8 "In3.Cu" signal "GND1")
		(10 "In4.Cu" signal "IN2")
		(12 "In5.Cu" signal "GND2")
		(14 "In6.Cu" signal "IN3")
		(16 "In7.Cu" signal "GND3")
		(18 "In8.Cu" signal "VCC")
		(20 "In9.Cu" signal "VCC1")
		(22 "In10.Cu" signal "GND4")
		(24 "In11.Cu" signal "IN4")
		(26 "In12.Cu" signal "GND5")
		(28 "In13.Cu" signal "IN5")
		(30 "In14.Cu" signal "GND6")
		(32 "In15.Cu" signal "IN6")
		(34 "In16.Cu" signal "GND7")
		(2 "B.Cu" signal "BOTTOM")
		(9 "F.Adhes" user "F.Adhesive")
		(11 "B.Adhes" user "B.Adhesive")
		(13 "F.Paste" user "Package Geometry/Pastemask Top")
		(15 "B.Paste" user "Package Geometry/Pastemask Bottom")
		(5 "F.SilkS" user "Ref Des/Silkscreen Top")
		(7 "B.SilkS" user "Ref Des/Silkscreen Bottom")
		(1 "F.Mask" user "Board Geometry/Soldermask Top")
		(3 "B.Mask" user "Board Geometry/Soldermask Bottom")
		(17 "Dwgs.User" user "User.Drawings")
		(19 "Cmts.User" user "User.Comments")
		(21 "Eco1.User" user "User.Eco1")
		(23 "Eco2.User" user "User.Eco2")
		(25 "Edge.Cuts" user "Board Geometry/Outline")
		(27 "Margin" user)
		(31 "F.CrtYd" user "Package Geometry/Place Bound Top")
		(29 "B.CrtYd" user "Package Geometry/Place Bound Bottom")
		(35 "F.Fab" user "Ref Des/Assembly Top")
		(33 "B.Fab" user "Ref Des/Assembly Bottom")
	)
	(footprint ""
		(layer "F.Cu")
		(at 359.870248 -251.76988 90)
		(property "Reference" "U2"
			(at -74.416158 -44.488608 0)
			(unlocked yes)
			(layer "F.SilkS")
			(effects
				(font
					(size 1.6002 1.1938)
					(thickness 0.1524)
				)
				(justify left)
			)
		)
		(property "Value" ""
			(at 0 0 90)
			(layer "F.Fab")
			(effects
				(font
					(size 1.27 1.27)
				)
			)
		)
		(duplicate_pad_numbers_are_jumpers no)
		(pad "EN84" smd oval
			(at 31.727902 25.664414 315)
			(size 0.381 0.4826)
			(drill
				(offset 0 -0.0508)
			)
			(layers "F.Cu" "F.Mask" "F.Paste")
			(net "PVCCFA_EHV_FIVRA_CPU0")
		)
		(pad "EN86" smd oval
			(at 33.355534 25.664414 315)
			(size 0.381 0.4826)
			(drill
				(offset 0 -0.0508)
			)
			(layers "F.Cu" "F.Mask" "F.Paste")
			(net "Net_665")
		)
		(pad "EN88" smd oval
			(at 34.98342 25.664414 315)
			(size 0.381 0.4826)
			(drill
				(offset 0 -0.0508)
			)
			(layers "F.Cu" "F.Mask" "F.Paste")
			(net "GND")
		)
		(pad "EP4" smd oval
			(at -34.98342 26.024586 225)
			(size 0.381 0.4826)
			(drill
				(offset 0 -0.0508)
			)
			(layers "F.Cu" "F.Mask" "F.Paste")
			(net "M_G_CPU0_SB_DQ<30>")
		)
		(pad "EP6" smd oval
			(at -33.355534 26.024586 225)
			(size 0.381 0.4826)
			(drill
				(offset 0 -0.0508)
			)
			(layers "F.Cu" "F.Mask" "F.Paste")
			(net "M_G_CPU0_SB_DQS_DN<3>")
		)
		(pad "EP8" smd oval
			(at -31.727902 26.024586 225)
			(size 0.381 0.4826)
			(drill
				(offset 0 -0.0508)
			)
			(layers "F.Cu" "F.Mask" "F.Paste")
			(net "M_G_CPU0_SB_DQ<26>")
		)
		(pad "EP10" smd circle
			(at -30.100016 26.024586 270)
			(size 0.4318 0.4318)
			(layers "F.Cu" "F.Mask" "F.Paste")
			(net "M_F_CPU0_SB_DQ<23>")
		)
		(pad "EP12" smd circle
			(at -28.472384 26.024586 270)
			(size 0.4318 0.4318)
			(layers "F.Cu" "F.Mask" "F.Paste")
			(net "M_F_CPU0_SB_DQS_DP<7>")
		)
		(pad "EP14" smd circle
			(at -26.844498 26.024586 270)
			(size 0.4318 0.4318)
			(layers "F.Cu" "F.Mask" "F.Paste")
			(net "M_F_CPU0_SB_DQ<18>")
		)
		(pad "EP16" smd circle
			(at -25.216612 26.024586 270)
			(size 0.4318 0.4318)
			(layers "F.Cu" "F.Mask" "F.Paste")
			(net "M_E_CPU0_SB_DQ<31>")
		)
		(pad "EP18" smd circle
			(at -23.58898 26.024586 270)
			(size 0.4318 0.4318)
			(layers "F.Cu" "F.Mask" "F.Paste")
			(net "M_E_CPU0_SB_DQS_DP<8>")
		)
		(pad "EP20" smd circle
			(at -21.961094 26.024586 270)
			(size 0.4318 0.4318)
			(layers "F.Cu" "F.Mask" "F.Paste")
			(net "M_E_CPU0_SB_DQ<26>")
		)
		(pad "EP22" smd circle
			(at -20.333462 26.024586 270)
			(size 0.4318 0.4318)
			(layers "F.Cu" "F.Mask" "F.Paste")
			(net "M_E_CPU0_SB_DQ<23>")
		)
		(pad "EP24" smd circle
			(at -18.705576 26.024586 270)
			(size 0.4318 0.4318)
			(layers "F.Cu" "F.Mask" "F.Paste")
			(net "M_E_CPU0_SB_DQS_DP<7>")
		)
		(pad "EP26" smd circle
			(at -17.07769 26.024586 270)
			(size 0.4318 0.4318)
			(layers "F.Cu" "F.Mask" "F.Paste")
			(net "M_E_CPU0_SB_DQ<18>")
		)
		(pad "EP28" smd circle
			(at -15.450058 26.024586 270)
			(size 0.4318 0.4318)
			(layers "F.Cu" "F.Mask" "F.Paste")
			(net "M_E_CPU0_SB_DQ<15>")
		)
		(pad "EP30" smd circle
			(at -13.822426 26.024586 270)
			(size 0.4318 0.4318)
			(layers "F.Cu" "F.Mask" "F.Paste")
			(net "M_E_CPU0_SB_DQS_DP<6>")
		)
		(pad "EP32" smd circle
			(at -12.19454 26.024586 270)
			(size 0.4318 0.4318)
			(layers "F.Cu" "F.Mask" "F.Paste")
			(net "M_E_CPU0_SB_DQ<10>")
		)
		(pad "EP34" smd circle
			(at -10.566654 26.024586 270)
			(size 0.4318 0.4318)
			(layers "F.Cu" "F.Mask" "F.Paste")
			(net "M_E_CPU0_SB_CB<3>")
		)
		(pad "EP36" smd circle
			(at -8.939022 26.024586 270)
			(size 0.4318 0.4318)
			(layers "F.Cu" "F.Mask" "F.Paste")
			(net "M_E_CPU0_SB_DQS_DP<4>")
		)
		(pad "EP38" smd circle
			(at -7.311136 26.024586 270)
			(size 0.4318 0.4318)
			(layers "F.Cu" "F.Mask" "F.Paste")
			(net "M_E_CPU0_SB_CB<6>")
		)
		(pad "EP40" smd circle
			(at -5.68325 26.024586 270)
			(size 0.4318 0.4318)
			(layers "F.Cu" "F.Mask" "F.Paste")
			(net "M_E_CPU0_SB_CS_N<0>")
		)
		(pad "EP42" smd circle
			(at -4.055618 26.024586 270)
			(size 0.4318 0.4318)
			(layers "F.Cu" "F.Mask" "F.Paste")
			(net "M_E_CPU0_SB_PAR")
		)
		(pad "EP44" smd oval
			(at -2.427732 26.024586 270)
			(size 0.381 0.4826)
			(drill
				(offset 0 -0.0508)
			)
			(layers "F.Cu" "F.Mask" "F.Paste")
			(net "M_E_CPU0_SB_CA<3>")
		)
		(pad "EP47" smd oval
			(at 1.613916 26.134314 270)
			(size 0.381 0.4826)
			(drill
				(offset 0 -0.0508)
			)
			(layers "F.Cu" "F.Mask" "F.Paste")
			(net "M_E_CPU0_SA_CA<5>")
		)
		(pad "EP49" smd circle
			(at 3.241802 26.134314 270)
			(size 0.4318 0.4318)
			(layers "F.Cu" "F.Mask" "F.Paste")
			(net "M_E_CPU0_SA_CA<0>")
		)
		(pad "EP51" smd circle
			(at 4.869434 26.134314 270)
			(size 0.4318 0.4318)
			(layers "F.Cu" "F.Mask" "F.Paste")
			(net "M_E_CPU0_SA_CS_N<0>")
		)
		(pad "EP53" smd circle
			(at 6.49732 26.134314 270)
			(size 0.4318 0.4318)
			(layers "F.Cu" "F.Mask" "F.Paste")
			(net "M_E_CPU0_SA_CB<7>")
		)
		(pad "EP55" smd circle
			(at 8.124952 26.134314 270)
			(size 0.4318 0.4318)
			(layers "F.Cu" "F.Mask" "F.Paste")
			(net "M_E_CPU0_SA_DQS_DP<9>")
		)
		(pad "EP57" smd circle
			(at 9.752838 26.134314 270)
			(size 0.4318 0.4318)
			(layers "F.Cu" "F.Mask" "F.Paste")
			(net "M_E_CPU0_SA_CB<2>")
		)
		(pad "EP59" smd circle
			(at 11.380724 26.134314 270)
			(size 0.4318 0.4318)
			(layers "F.Cu" "F.Mask" "F.Paste")
			(net "M_E_CPU0_SA_DQ<31>")
		)
		(pad "EP61" smd circle
			(at 13.008356 26.134314 270)
			(size 0.4318 0.4318)
			(layers "F.Cu" "F.Mask" "F.Paste")
			(net "M_E_CPU0_SA_DQS_DP<8>")
		)
		(pad "EP63" smd circle
			(at 14.635988 26.134314 270)
			(size 0.4318 0.4318)
			(layers "F.Cu" "F.Mask" "F.Paste")
			(net "M_E_CPU0_SA_DQ<26>")
		)
		(pad "EP65" smd circle
			(at 16.263874 26.134314 270)
			(size 0.4318 0.4318)
			(layers "F.Cu" "F.Mask" "F.Paste")
			(net "M_E_CPU0_SA_DQ<23>")
		)
		(pad "EP67" smd circle
			(at 17.89176 26.134314 270)
			(size 0.4318 0.4318)
			(layers "F.Cu" "F.Mask" "F.Paste")
			(net "GND")
		)
		(pad "EP69" smd circle
			(at 19.519392 26.134314 270)
			(size 0.4318 0.4318)
			(layers "F.Cu" "F.Mask" "F.Paste")
			(net "GND")
		)
		(pad "EP71" smd circle
			(at 21.147278 26.134314 270)
			(size 0.4318 0.4318)
			(layers "F.Cu" "F.Mask" "F.Paste")
			(net "GND")
		)
		(pad "EP73" smd circle
			(at 22.77491 26.134314 270)
			(size 0.4318 0.4318)
			(layers "F.Cu" "F.Mask" "F.Paste")
			(net "M_E_CPU0_SA_DQ<6>")
		)
		(pad "EP75" smd circle
			(at 24.402796 26.134314 270)
			(size 0.4318 0.4318)
			(layers "F.Cu" "F.Mask" "F.Paste")
			(net "M_E_CPU0_SA_DQS_DN<0>")
		)
		(pad "EP77" smd circle
			(at 26.030682 26.134314 270)
			(size 0.4318 0.4318)
			(layers "F.Cu" "F.Mask" "F.Paste")
			(net "GND")
		)
		(pad "EP79" smd circle
			(at 27.658314 26.134314 270)
			(size 0.4318 0.4318)
			(layers "F.Cu" "F.Mask" "F.Paste")
			(net "M_E_CPU0_SA_DQ<2>")
		)
		(pad "EP81" smd circle
			(at 29.2862 26.134314 270)
			(size 0.4318 0.4318)
			(layers "F.Cu" "F.Mask" "F.Paste")
			(net "GND")
		)
		(pad "EP83" smd oval
			(at 30.914086 26.134314 315)
			(size 0.381 0.4826)
			(drill
				(offset 0 -0.0508)
			)
			(layers "F.Cu" "F.Mask" "F.Paste")
			(net "GND")
		)
		(pad "EP85" smd oval
			(at 32.541718 26.134314 315)
			(size 0.381 0.4826)
			(drill
				(offset 0 -0.0508)
			)
			(layers "F.Cu" "F.Mask" "F.Paste")
			(net "Net_689")
		)
		(pad "EP87" smd oval
			(at 34.169604 26.134314 315)
			(size 0.381 0.4826)
			(drill
				(offset 0 -0.0508)
			)
			(layers "F.Cu" "F.Mask" "F.Paste")
			(net "Net_660")
		)
		(pad "ER5" smd oval
			(at -34.169604 26.494486 225)
			(size 0.381 0.4826)
			(drill
				(offset 0 -0.0508)
			)
			(layers "F.Cu" "F.Mask" "F.Paste")
			(net "GND")
		)
		(pad "ER7" smd oval
			(at -32.541718 26.494486 225)
			(size 0.381 0.4826)
			(drill
				(offset 0 -0.0508)
			)
			(layers "F.Cu" "F.Mask" "F.Paste")
			(net "GND")
		)
		(pad "ER9" smd oval
			(at -30.914086 26.494486 225)
			(size 0.381 0.4826)
			(drill
				(offset 0 -0.0508)
			)
			(layers "F.Cu" "F.Mask" "F.Paste")
			(net "GND")
		)
		(pad "ER11" smd circle
			(at -29.2862 26.494486 270)
			(size 0.4318 0.4318)
			(layers "F.Cu" "F.Mask" "F.Paste")
			(net "M_F_CPU0_SB_DQ<22>")
		)
		(pad "ER13" smd circle
			(at -27.658314 26.494486 270)
			(size 0.4318 0.4318)
			(layers "F.Cu" "F.Mask" "F.Paste")
			(net "M_F_CPU0_SB_DQ<19>")
		)
		(pad "ER15" smd circle
			(at -26.030682 26.494486 270)
			(size 0.4318 0.4318)
			(layers "F.Cu" "F.Mask" "F.Paste")
			(net "GND")
		)
		(pad "ER17" smd circle
			(at -24.402796 26.494486 270)
			(size 0.4318 0.4318)
			(layers "F.Cu" "F.Mask" "F.Paste")
			(net "M_E_CPU0_SB_DQ<30>")
		)
		(pad "ER19" smd circle
			(at -22.77491 26.494486 270)
			(size 0.4318 0.4318)
			(layers "F.Cu" "F.Mask" "F.Paste")
			(net "M_E_CPU0_SB_DQ<27>")
		)
		(pad "ER21" smd circle
			(at -21.147278 26.494486 270)
			(size 0.4318 0.4318)
			(layers "F.Cu" "F.Mask" "F.Paste")
			(net "GND")
		)
		(pad "ER23" smd circle
			(at -19.519392 26.494486 270)
			(size 0.4318 0.4318)
			(layers "F.Cu" "F.Mask" "F.Paste")
			(net "M_E_CPU0_SB_DQ<22>")
		)
		(pad "ER25" smd circle
			(at -17.89176 26.494486 270)
			(size 0.4318 0.4318)
			(layers "F.Cu" "F.Mask" "F.Paste")
			(net "M_E_CPU0_SB_DQ<19>")
		)
		(pad "ER27" smd circle
			(at -16.263874 26.494486 270)
			(size 0.4318 0.4318)
			(layers "F.Cu" "F.Mask" "F.Paste")
			(net "GND")
		)
		(pad "ER29" smd circle
			(at -14.635988 26.494486 270)
			(size 0.4318 0.4318)
			(layers "F.Cu" "F.Mask" "F.Paste")
			(net "M_E_CPU0_SB_DQ<14>")
		)
		(pad "ER31" smd circle
			(at -13.008356 26.494486 270)
			(size 0.4318 0.4318)
			(layers "F.Cu" "F.Mask" "F.Paste")
			(net "M_E_CPU0_SB_DQ<11>")
		)
		(pad "ER33" smd circle
			(at -11.380724 26.494486 270)
			(size 0.4318 0.4318)
			(layers "F.Cu" "F.Mask" "F.Paste")
			(net "GND")
		)
		(pad "ER35" smd circle
			(at -9.752838 26.494486 270)
			(size 0.4318 0.4318)
			(layers "F.Cu" "F.Mask" "F.Paste")
			(net "M_E_CPU0_SB_CB<2>")
		)
		(pad "ER37" smd circle
			(at -8.124952 26.494486 270)
			(size 0.4318 0.4318)
			(layers "F.Cu" "F.Mask" "F.Paste")
			(net "M_E_CPU0_SB_CB<7>")
		)
		(pad "ER39" smd circle
			(at -6.49732 26.494486 270)
			(size 0.4318 0.4318)
			(layers "F.Cu" "F.Mask" "F.Paste")
			(net "GND")
		)
		(pad "ER41" smd circle
			(at -4.869434 26.494486 270)
			(size 0.4318 0.4318)
			(layers "F.Cu" "F.Mask" "F.Paste")
			(net "GND")
		)
		(pad "ER43" smd oval
			(at -3.241802 26.494486 270)
			(size 0.381 0.4826)
			(drill
				(offset 0 -0.0508)
			)
			(layers "F.Cu" "F.Mask" "F.Paste")
			(net "GND")
		)
		(pad "ER48" smd oval
			(at 2.427732 26.604468 270)
			(size 0.381 0.4826)
			(drill
				(offset 0 -0.0508)
			)
			(layers "F.Cu" "F.Mask" "F.Paste")
			(net "GND")
		)
		(pad "ER50" smd circle
			(at 4.055618 26.604468 270)
			(size 0.4318 0.4318)
			(layers "F.Cu" "F.Mask" "F.Paste")
			(net "GND")
		)
		(pad "ER52" smd circle
			(at 5.68325 26.604468 270)
			(size 0.4318 0.4318)
			(layers "F.Cu" "F.Mask" "F.Paste")
			(net "GND")
		)
		(pad "ER54" smd circle
			(at 7.311136 26.604468 270)
			(size 0.4318 0.4318)
			(layers "F.Cu" "F.Mask" "F.Paste")
			(net "M_E_CPU0_SA_CB<6>")
		)
		(pad "ER56" smd circle
			(at 8.939022 26.604468 270)
			(size 0.4318 0.4318)
			(layers "F.Cu" "F.Mask" "F.Paste")
			(net "M_E_CPU0_SA_CB<3>")
		)
		(pad "ER58" smd circle
			(at 10.566654 26.604468 270)
			(size 0.4318 0.4318)
			(layers "F.Cu" "F.Mask" "F.Paste")
			(net "GND")
		)
		(pad "ER60" smd circle
			(at 12.19454 26.604468 270)
			(size 0.4318 0.4318)
			(layers "F.Cu" "F.Mask" "F.Paste")
			(net "M_E_CPU0_SA_DQ<30>")
		)
		(pad "ER62" smd oval
			(at 13.822426 26.604468 270)
			(size 0.381 0.4826)
			(drill
				(offset 0 -0.0508)
			)
			(layers "F.Cu" "F.Mask" "F.Paste")
			(net "M_E_CPU0_SA_DQ<27>")
		)
		(pad "ER64" smd oval
			(at 15.450058 26.604468 270)
			(size 0.381 0.4826)
			(drill
				(offset 0 -0.0508)
			)
			(layers "F.Cu" "F.Mask" "F.Paste")
			(net "GND")
		)
		(pad "ER66" smd oval
			(at 17.07769 26.604468 270)
			(size 0.381 0.4826)
			(drill
				(offset 0 -0.0508)
			)
			(layers "F.Cu" "F.Mask" "F.Paste")
			(net "M_E_CPU0_SA_DQ<20>")
		)
		(pad "ER68" smd oval
			(at 18.705576 26.604468 270)
			(size 0.381 0.4826)
			(drill
				(offset 0 -0.0508)
			)
			(layers "F.Cu" "F.Mask" "F.Paste")
			(net "M_E_CPU0_SA_DQ<19>")
		)
		(pad "ER70" smd oval
			(at 20.333462 26.604468 270)
			(size 0.381 0.4826)
			(drill
				(offset 0 -0.0508)
			)
			(layers "F.Cu" "F.Mask" "F.Paste")
			(net "GND")
		)
		(pad "ER72" smd oval
			(at 21.961094 26.604468 270)
			(size 0.381 0.4826)
			(drill
				(offset 0 -0.0508)
			)
			(layers "F.Cu" "F.Mask" "F.Paste")
			(net "M_E_CPU0_SA_DQ<7>")
		)
		(pad "ER74" smd oval
			(at 23.58898 26.604468 270)
			(size 0.381 0.4826)
			(drill
				(offset 0 -0.0508)
			)
			(layers "F.Cu" "F.Mask" "F.Paste")
			(net "GND")
		)
		(pad "ER76" smd oval
			(at 25.216612 26.604468 270)
			(size 0.381 0.4826)
			(drill
				(offset 0 -0.0508)
			)
			(layers "F.Cu" "F.Mask" "F.Paste")
			(net "M_E_CPU0_SA_DQ<3>")
		)
		(pad "ER78" smd oval
			(at 26.844498 26.604468 270)
			(size 0.381 0.4826)
			(drill
				(offset 0 -0.0508)
			)
			(layers "F.Cu" "F.Mask" "F.Paste")
			(net "GND")
		)
		(pad "ER80" smd oval
			(at 28.472384 26.604468 270)
			(size 0.381 0.4826)
			(drill
				(offset 0 -0.0508)
			)
			(layers "F.Cu" "F.Mask" "F.Paste")
			(net "GND")
		)
		(pad "ER82" smd oval
			(at 30.100016 26.604468 315)
			(size 0.381 0.4826)
			(drill
				(offset 0 -0.0508)
			)
			(layers "F.Cu" "F.Mask" "F.Paste")
			(net "GND")
		)
		(pad "ER84" smd oval
			(at 31.727902 26.604468 315)
			(size 0.381 0.4826)
			(drill
				(offset 0 -0.0508)
			)
			(layers "F.Cu" "F.Mask" "F.Paste")
			(net "GND")
		)
		(pad "ER86" smd oval
			(at 33.355534 26.604468 315)
			(size 0.381 0.4826)
			(drill
				(offset 0 -0.0508)
			)
			(layers "F.Cu" "F.Mask" "F.Paste")
			(net "GND")
		)
		(pad "ET8" smd oval
			(at -31.727902 26.964132 225)
			(size 0.381 0.4826)
			(drill
				(offset 0 -0.0508)
			)
			(layers "F.Cu" "F.Mask" "F.Paste")
			(net "M_G_CPU0_SB_DQ<27>")
		)
		(pad "ET10" smd oval
			(at -30.100016 26.964132 225)
			(size 0.381 0.4826)
			(drill
				(offset 0 -0.0508)
			)
			(layers "F.Cu" "F.Mask" "F.Paste")
			(net "GND")
		)
		(pad "ET12" smd oval
			(at -28.472384 26.964132 270)
			(size 0.381 0.4826)
			(drill
				(offset 0 -0.0508)
			)
			(layers "F.Cu" "F.Mask" "F.Paste")
			(net "M_F_CPU0_SB_DQS_DN<7>")
		)
		(pad "ET14" smd oval
			(at -26.844498 26.964132 270)
			(size 0.381 0.4826)
			(drill
				(offset 0 -0.0508)
			)
			(layers "F.Cu" "F.Mask" "F.Paste")
			(net "GND")
		)
		(pad "ET16" smd oval
			(at -25.216612 26.964132 270)
			(size 0.381 0.4826)
			(drill
				(offset 0 -0.0508)
			)
			(layers "F.Cu" "F.Mask" "F.Paste")
			(net "GND")
		)
		(pad "ET18" smd oval
			(at -23.58898 26.964132 270)
			(size 0.381 0.4826)
			(drill
				(offset 0 -0.0508)
			)
			(layers "F.Cu" "F.Mask" "F.Paste")
			(net "M_E_CPU0_SB_DQS_DN<8>")
		)
		(pad "ET20" smd oval
			(at -21.961094 26.964132 270)
			(size 0.381 0.4826)
			(drill
				(offset 0 -0.0508)
			)
			(layers "F.Cu" "F.Mask" "F.Paste")
			(net "GND")
		)
		(pad "ET22" smd oval
			(at -20.333462 26.964132 270)
			(size 0.381 0.4826)
			(drill
				(offset 0 -0.0508)
			)
			(layers "F.Cu" "F.Mask" "F.Paste")
			(net "GND")
		)
		(pad "ET24" smd oval
			(at -18.705576 26.964132 270)
			(size 0.381 0.4826)
			(drill
				(offset 0 -0.0508)
			)
			(layers "F.Cu" "F.Mask" "F.Paste")
			(net "M_E_CPU0_SB_DQS_DN<7>")
		)
		(pad "ET26" smd oval
			(at -17.07769 26.964132 270)
			(size 0.381 0.4826)
			(drill
				(offset 0 -0.0508)
			)
			(layers "F.Cu" "F.Mask" "F.Paste")
			(net "GND")
		)
		(pad "ET28" smd oval
			(at -15.450058 26.964132 270)
			(size 0.381 0.4826)
			(drill
				(offset 0 -0.0508)
			)
			(layers "F.Cu" "F.Mask" "F.Paste")
			(net "GND")
		)
		(pad "ET30" smd oval
			(at -13.822426 26.964132 270)
			(size 0.381 0.4826)
			(drill
				(offset 0 -0.0508)
			)
			(layers "F.Cu" "F.Mask" "F.Paste")
			(net "M_E_CPU0_SB_DQS_DN<6>")
		)
		(pad "ET32" smd oval
			(at -12.19454 26.964132 270)
			(size 0.381 0.4826)
			(drill
				(offset 0 -0.0508)
			)
			(layers "F.Cu" "F.Mask" "F.Paste")
			(net "GND")
		)
		(pad "ET34" smd oval
			(at -10.566654 26.964132 270)
			(size 0.381 0.4826)
			(drill
				(offset 0 -0.0508)
			)
			(layers "F.Cu" "F.Mask" "F.Paste")
			(net "GND")
		)
		(pad "ET36" smd oval
			(at -8.939022 26.964132 270)
			(size 0.381 0.4826)
			(drill
				(offset 0 -0.0508)
			)
			(layers "F.Cu" "F.Mask" "F.Paste")
			(net "M_E_CPU0_SB_DQS_DN<4>")
		)
	)
)
